# S9S_MB_2U (Grand Teton) — schematic netlist excerpt (pin names and nets, part order shuffled) for the footprints in the layout excerpt that follows; sources: Cadence DE-HDL packaged netlist, KiCad conversion of 03242023_DA0F0TMBIJ0_F0T_Motherboard_J_brd_V01_OCP.brd

PR3961  Q_RES  6.8K 1% EMPTY  pkg 0402LF  page 192 : A = P12V_E1S_UV_0 ; B = P12V_E1S_OV_0
C144  Q_CAP_DIFFBUS  DIFF BUS_0.22UF 6.3V 20% X6S  pkg C0201  page 178 : \1\ = DMI_CPU0_PCH_TX_C_DP<5> ; \2\ = DMI_CPU0_PCH_TX_DP<5>

(kicad_pcb
	(version 20260206)
	(generator "pcbnew")
	(generator_version "10.0")
	(general
		(thickness 1.6)
		(legacy_teardrops no)
	)
	(paper "A4")
	(title_block
		(title "03242023_DA0F0TMBIJ0_F0T_Motherboard_J_brd_V01_OCP.brd")
		(comment 1 "Grand Teton / footprints 305-306 of 6105")
	)
	(layers
		(0 "F.Cu" signal "TOP")
		(4 "In1.Cu" signal "GND")
		(6 "In2.Cu" signal "IN1")
		(8 "In3.Cu" signal "GND1")
		(10 "In4.Cu" signal "IN2")
		(12 "In5.Cu" signal "GND2")
		(14 "In6.Cu" signal "IN3")
		(16 "In7.Cu" signal "GND3")
		(18 "In8.Cu" signal "VCC")
		(20 "In9.Cu" signal "VCC1")
		(22 "In10.Cu" signal "GND4")
		(24 "In11.Cu" signal "IN4")
		(26 "In12.Cu" signal "GND5")
		(28 "In13.Cu" signal "IN5")
		(30 "In14.Cu" signal "GND6")
		(32 "In15.Cu" signal "IN6")
		(34 "In16.Cu" signal "GND7")
		(2 "B.Cu" signal "BOTTOM")
		(9 "F.Adhes" user "F.Adhesive")
		(11 "B.Adhes" user "B.Adhesive")
		(13 "F.Paste" user "Package Geometry/Pastemask Top")
		(15 "B.Paste" user "Package Geometry/Pastemask Bottom")
		(5 "F.SilkS" user "Ref Des/Silkscreen Top")
		(7 "B.SilkS" user "Ref Des/Silkscreen Bottom")
		(1 "F.Mask" user "Board Geometry/Soldermask Top")
		(3 "B.Mask" user "Board Geometry/Soldermask Bottom")
		(17 "Dwgs.User" user "User.Drawings")
		(19 "Cmts.User" user "User.Comments")
		(21 "Eco1.User" user "User.Eco1")
		(23 "Eco2.User" user "User.Eco2")
		(25 "Edge.Cuts" user "Board Geometry/Outline")
		(27 "Margin" user)
		(31 "F.CrtYd" user "Package Geometry/Place Bound Top")
		(29 "B.CrtYd" user "Package Geometry/Place Bound Bottom")
		(35 "F.Fab" user "Ref Des/Assembly Top")
		(33 "B.Fab" user "Ref Des/Assembly Bottom")
	)
	(footprint ""
		(layer "F.Cu")
		(at 351.6757 -65.354962)
		(property "Reference" "C144"
			(at 0 0 0)
			(layer "F.SilkS")
			(hide yes)
			(effects
				(font
					(size 1.27 1.27)
				)
			)
		)
		(property "Value" ""
			(at 0 0 0)
			(layer "F.Fab")
			(effects
				(font
					(size 1.27 1.27)
				)
			)
		)
		(duplicate_pad_numbers_are_jumpers no)
		(fp_line
			(start -0.299974 -0.150114)
			(end 0.299974 -0.150114)
			(stroke
				(width 0.1)
				(type default)
			)
			(layer "F.Fab")
		)
		(fp_line
			(start -0.299974 0.150114)
			(end -0.299974 -0.150114)
			(stroke
				(width 0.1)
				(type default)
			)
			(layer "F.Fab")
		)
		(fp_line
			(start 0.299974 -0.150114)
			(end 0.299974 0.150114)
			(stroke
				(width 0.1)
				(type default)
			)
			(layer "F.Fab")
		)
		(fp_line
			(start 0.299974 0.150114)
			(end -0.299974 0.150114)
			(stroke
				(width 0.1)
				(type default)
			)
			(layer "F.Fab")
		)
		(pad "1" smd rect
			(at -0.2667 0)
			(size 0.3048 0.381)
			(layers "F.Cu" "F.Mask" "F.Paste")
			(net "DMI_CPU0_PCH_TX_C_DP<5>")
		)
		(pad "2" smd rect
			(at 0.2667 0)
			(size 0.3048 0.381)
			(layers "F.Cu" "F.Mask" "F.Paste")
			(net "DMI_CPU0_PCH_TX_DP<5>")
		)
		(zone
			(layer "In1.Cu")
			(hatch none 0.5)
			(connect_pads
				(clearance 0)
			)
			(min_thickness 0.25)
			(keepout
				(tracks not_allowed)
				(vias allowed)
				(pads allowed)
				(copperpour not_allowed)
				(footprints allowed)
			)
			(placement
				(enabled no)
				(sheetname "")
			)
			(fill
				(thermal_gap 0.5)
				(thermal_bridge_width 0.5)
				(island_removal_mode 0)
			)
			(polygon
				(pts
					(arc
						(start 351.282 -65.113662)
						(mid 351.228118 -65.13598)
						(end 351.2058 -65.189862)
					)
					(arc
						(start 351.2058 -65.520062)
						(mid 351.228118 -65.573944)
						(end 351.282 -65.596262)
					)
					(arc
						(start 351.536 -65.596262)
						(mid 351.589882 -65.573944)
						(end 351.6122 -65.520062)
					)
					(arc
						(start 351.6122 -65.189862)
						(mid 351.589882 -65.13598)
						(end 351.536 -65.113662)
					)
				)
			)
		)
		(zone
			(layer "In1.Cu")
			(hatch none 0.5)
			(connect_pads
				(clearance 0)
			)
			(min_thickness 0.25)
			(keepout
				(tracks not_allowed)
				(vias allowed)
				(pads allowed)
				(copperpour not_allowed)
				(footprints allowed)
			)
			(placement
				(enabled no)
				(sheetname "")
			)
			(fill
				(thermal_gap 0.5)
				(thermal_bridge_width 0.5)
				(island_removal_mode 0)
			)
			(polygon
				(pts
					(arc
						(start 351.8154 -65.113662)
						(mid 351.761518 -65.13598)
						(end 351.7392 -65.189862)
					)
					(arc
						(start 351.7392 -65.520062)
						(mid 351.761518 -65.573944)
						(end 351.8154 -65.596262)
					)
					(arc
						(start 352.0694 -65.596262)
						(mid 352.123282 -65.573944)
						(end 352.1456 -65.520062)
					)
					(arc
						(start 352.1456 -65.189862)
						(mid 352.123282 -65.13598)
						(end 352.0694 -65.113662)
					)
				)
			)
		)
	)
	(footprint ""
		(layer "F.Cu")
		(at 249.916696 -43.556682 180)
		(property "Reference" "PR3961"
			(at 0 0 180)
			(layer "F.SilkS")
			(hide yes)
			(effects
				(font
					(size 1.27 1.27)
				)
			)
		)
		(property "Value" ""
			(at 0 0 180)
			(layer "F.Fab")
			(effects
				(font
					(size 1.27 1.27)
				)
			)
		)
		(duplicate_pad_numbers_are_jumpers no)
		(fp_line
			(start 0.7874 0.4064)
			(end -0.7874 0.4064)
			(stroke
				(width 0.1524)
				(type default)
			)
			(layer "F.SilkS")
		)
		(fp_line
			(start 0.7874 -0.4064)
			(end 0.7874 0.4064)
			(stroke
				(width 0.1524)
				(type default)
			)
			(layer "F.SilkS")
		)
		(fp_line
			(start -0.7874 0.4064)
			(end -0.7874 -0.4064)
			(stroke
				(width 0.1524)
				(type default)
			)
			(layer "F.SilkS")
		)
		(fp_line
			(start -0.7874 -0.4064)
			(end 0.7874 -0.4064)
			(stroke
				(width 0.1524)
				(type default)
			)
			(layer "F.SilkS")
		)
		(fp_line
			(start 0.67945 0.3048)
			(end 0.120396 0.3048)
			(stroke
				(width 0.1)
				(type default)
			)
			(layer "F.Fab")
		)
		(fp_line
			(start 0.67945 -0.3048)
			(end 0.67945 0.3048)
			(stroke
				(width 0.1)
				(type default)
			)
			(layer "F.Fab")
		)
		(fp_line
			(start 0.12065 -0.2794)
			(end 0.12065 -0.3048)
			(stroke
				(width 0.1)
				(type default)
			)
			(layer "F.Fab")
		)
		(fp_line
			(start 0.12065 -0.3048)
			(end 0.67945 -0.3048)
			(stroke
				(width 0.1)
				(type default)
			)
			(layer "F.Fab")
		)
		(fp_line
			(start 0.120396 0.3048)
			(end 0.120396 0.2794)
			(stroke
				(width 0.1)
				(type default)
			)
			(layer "F.Fab")
		)
		(fp_line
			(start 0.120396 0.2794)
			(end -0.12065 0.2794)
			(stroke
				(width 0.1)
				(type default)
			)
			(layer "F.Fab")
		)
		(fp_line
			(start -0.12065 0.3048)
			(end -0.67945 0.3048)
			(stroke
				(width 0.1)
				(type default)
			)
			(layer "F.Fab")
		)
		(fp_line
			(start -0.12065 0.2794)
			(end -0.12065 0.3048)
			(stroke
				(width 0.1)
				(type default)
			)
			(layer "F.Fab")
		)
		(fp_line
			(start -0.12065 -0.2794)
			(end 0.12065 -0.2794)
			(stroke
				(width 0.1)
				(type default)
			)
			(layer "F.Fab")
		)
		(fp_line
			(start -0.12065 -0.305054)
			(end -0.12065 -0.2794)
			(stroke
				(width 0.1)
				(type default)
			)
			(layer "F.Fab")
		)
		(fp_line
			(start -0.67945 0.3048)
			(end -0.67945 -0.305054)
			(stroke
				(width 0.1)
				(type default)
			)
			(layer "F.Fab")
		)
		(fp_line
			(start -0.67945 -0.305054)
			(end -0.12065 -0.305054)
			(stroke
				(width 0.1)
				(type default)
			)
			(layer "F.Fab")
		)
		(pad "1" smd circle
			(at -0.40005 0 180)
			(size 0 0)
			(layers "F.Cu" "F.Mask" "F.Paste")
			(net "P12V_E1S_UV_0")
		)
		(pad "2" smd circle
			(at 0.40005 0 180)
			(size 0 0)
			(layers "F.Cu" "F.Mask" "F.Paste")
			(net "P12V_E1S_OV_0")
		)
	)
)
